# BASEBOARD_FAB2 (Tioga Pass) — schematic netlist excerpt (pin names and nets, part order shuffled) for the footprints in the layout excerpt that follows; sources: Cadence DE-HDL packaged netlist, KiCad conversion of Wiwynn_Tioga_Pass_MB.brd

J4G3  SCONN288_H44441004  SCONN  pkg PIP  page 47
  \12v\(1)  = P12V_NVDIMM_ABC
  VSS(93)  = GND
  DQ(4)  = M_C_DQ<5>
  VSS(92)  = GND
  DQ(0)  = M_C_DQ<1>
  VSS(91)  = GND
  DQS9P  = M_C_DQS_DP<9>
  DQS9N  = M_C_DQS_DN<9>
  VSS(90)  = GND
  DQ(6)  = M_C_DQ<7>
  VSS(89)  = GND
  DQ(2)  = M_C_DQ<3>
  VSS(88)  = GND
  DQ(12)  = M_C_DQ<13>
  VSS(87)  = GND
  DQ(8)  = M_C_DQ<9>
  VSS(86)  = GND
  DQS10P  = M_C_DQS_DP<10>
  DQS10N  = M_C_DQS_DN<10>
  VSS(85)  = GND
  DQ(14)  = M_C_DQ<15>
  VSS(84)  = GND
  DQ(10)  = M_C_DQ<11>
  VSS(83)  = GND
  DQ(20)  = M_C_DQ<21>
  VSS(82)  = GND
  DQ(16)  = M_C_DQ<17>
  VSS(81)  = GND
  DQS11P  = M_C_DQS_DP<11>
  DQS11N  = M_C_DQS_DN<11>
  VSS(80)  = GND
  DQ(22)  = M_C_DQ<23>
  VSS(79)  = GND
  DQ(18)  = M_C_DQ<19>
  VSS(78)  = GND
  DQ(28)  = M_C_DQ<29>
  VSS(77)  = GND
  DQ(24)  = M_C_DQ<25>
  VSS(76)  = GND
  DQS12P  = M_C_DQS_DP<12>
  DQS12N  = M_C_DQS_DN<12>
  VSS(75)  = GND
  DQ(30)  = M_C_DQ<31>
  VSS(74)  = GND
  DQ(26)  = M_C_DQ<27>
  VSS(73)  = GND
  CB(4)  = M_C_ECC<5>
  VSS(72)  = GND
  CB(0)  = M_C_ECC<1>
  VSS(71)  = GND
  DQS17P  = M_C_DQS_DP<17>
  DQS17N  = M_C_DQS_DN<17>
  VSS(70)  = GND
  CB(6)  = M_C_ECC<7>
  VSS(69)  = GND
  CB(2)  = M_C_ECC<3>
  VSS(68)  = GND
  RESET_N  = M_ABC_RST_N
  VDD(25)  = PVDDQ_ABC
  CKE(0)  = M_C_CKE<0>
  VDD(24)  = PVDDQ_ABC
  ACT_N  = M_C_ACT_N
  BG(0)  = M_C_BG<0>
  VDD(23)  = PVDDQ_ABC
  A12  = M_C_MA<12>
  A9  = M_C_MA<9>
  VDD(22)  = PVDDQ_ABC
  A8  = M_C_MA<8>
  A6  = M_C_MA<6>
  VDD(21)  = PVDDQ_ABC
  A3  = M_C_MA<3>
  A1  = M_C_MA<1>
  VDD(20)  = PVDDQ_ABC
  CK0P  = M_C_CLK_DP<0>
  CK0N  = M_C_CLK_DN<0>
  VDD(19)  = PVDDQ_ABC
  VTT(1)  = PVTT_ABC
  EVENT_N  = FM_DIMM_EVENT_COD_N
  A0  = M_C_MA<0>
  VDD(18)  = PVDDQ_ABC
  BA(0)  = M_C_BA<0>
  A16_RAS_N  = M_C_MA<16>
  VDD(17)  = PVDDQ_ABC
  S0_N  = M_C_CS_N<0>
  VDD(16)  = PVDDQ_ABC
  A15_CAS_N  = M_C_MA<15>
  ODT(0)  = M_C_ODT<0>
  VDD(15)  = PVDDQ_ABC
  S1_N  = M_C_CS_N<1>
  VDD(14)  = PVDDQ_ABC
  ODT(1)  = M_C_ODT<1>
  VDD(13)  = PVDDQ_ABC
  S2_N_C(0)  = M_C_CS_N<2>
  VSS(67)  = GND
  DQ(36)  = M_C_DQ<37>
  VSS(66)  = GND
  DQ(32)  = M_C_DQ<33>
  VSS(65)  = GND
  DQS13P  = M_C_DQS_DP<13>
  DQS13N  = M_C_DQS_DN<13>
  VSS(64)  = GND
  DQ(38)  = M_C_DQ<39>
  VSS(63)  = GND
  DQ(34)  = M_C_DQ<35>
  VSS(62)  = GND
  DQ(44)  = M_C_DQ<45>
  VSS(61)  = GND
  DQ(40)  = M_C_DQ<41>
  VSS(60)  = GND
  DQS14P  = M_C_DQS_DP<14>
  DQS14N  = M_C_DQS_DN<14>
  VSS(59)  = GND
  DQ(46)  = M_C_DQ<47>
  VSS(58)  = GND
  DQ(42)  = M_C_DQ<43>
  VSS(57)  = GND
  DQ(52)  = M_C_DQ<53>
  VSS(56)  = GND
  DQ(48)  = M_C_DQ<49>
  VSS(55)  = GND
  DQS15P  = M_C_DQS_DP<15>
  DQS15N  = M_C_DQS_DN<15>
  VSS(54)  = GND
  DQ(54)  = M_C_DQ<55>
  VSS(53)  = GND
  DQ(50)  = M_C_DQ<51>
  VSS(52)  = GND
  DQ(60)  = M_C_DQ<61>
  VSS(51)  = GND
  DQ(56)  = M_C_DQ<57>
  VSS(50)  = GND
  DQS16P  = M_C_DQS_DP<16>
  DQS16N  = M_C_DQS_DN<16>
  VSS(49)  = GND
  DQ(62)  = M_C_DQ<63>
  VSS(48)  = GND
  DQ(58)  = M_C_DQ<59>
  VSS(47)  = GND
  SA(0)  = GND
  SA(1)  = GND
  SCL  = SMB_DDR_ABC_VPP_SCL
  VPP(4)  = PVPP_ABC
  VPP(3)  = PVPP_ABC
  RFU(2)  = TP_CH_C_DIMM_C0_RFU_2
  \12v\(0)  = P12V_NVDIMM_ABC
  VREFCA  = M_C_VREF
  VSS(46)  = GND
  DQ(5)  = M_C_DQ<4>
  VSS(45)  = GND
  DQ(1)  = M_C_DQ<0>
  VSS(44)  = GND
  DQS0N  = M_C_DQS_DN<0>
  DQS0P  = M_C_DQS_DP<0>
  VSS(43)  = GND
  DQ(7)  = M_C_DQ<6>
  VSS(42)  = GND
  DQ(3)  = M_C_DQ<2>
  VSS(41)  = GND
  DQ(13)  = M_C_DQ<12>
  VSS(40)  = GND
  DQ(9)  = M_C_DQ<8>
  VSS(39)  = GND
  DQS1N  = M_C_DQS_DN<1>
  DQS1P  = M_C_DQS_DP<1>
  VSS(38)  = GND
  DQ(15)  = M_C_DQ<14>
  VSS(37)  = GND
  DQ(11)  = M_C_DQ<10>
  VSS(36)  = GND
  DQ(21)  = M_C_DQ<20>
  VSS(35)  = GND
  DQ(17)  = M_C_DQ<16>
  VSS(34)  = GND
  DQS2N  = M_C_DQS_DN<2>
  DQS2P  = M_C_DQS_DP<2>
  VSS(33)  = GND
  DQ(23)  = M_C_DQ<22>
  VSS(32)  = GND
  DQ(19)  = M_C_DQ<18>
  VSS(31)  = GND
  DQ(29)  = M_C_DQ<28>
  VSS(30)  = GND
  DQ(25)  = M_C_DQ<24>
  VSS(29)  = GND
  DQS3N  = M_C_DQS_DN<3>
  DQS3P  = M_C_DQS_DP<3>
  VSS(28)  = GND
  DQ(31)  = M_C_DQ<30>
  VSS(27)  = GND
  DQ(27)  = M_C_DQ<26>
  VSS(26)  = GND
  CB(5)  = M_C_ECC<4>
  VSS(25)  = GND
  CB(1)  = M_C_ECC<0>
  VSS(24)  = GND
  DQS8N  = M_C_DQS_DN<8>
  DQS8P  = M_C_DQS_DP<8>
  VSS(23)  = GND
  CB(7)  = M_C_ECC<6>
  VSS(22)  = GND
  CB(3)  = M_C_ECC<2>
  VSS(21)  = GND
  CKE(1)  = M_C_CKE<1>
  VDD(12)  = PVDDQ_ABC
  RFU(0)  = TP_CH_C_DIMM_C0_RFU_0
  VDD(11)  = PVDDQ_ABC
  BG(1)  = M_C_BG<1>
  ALERT_N  = M_C_ALERT_N
  VDD(10)  = PVDDQ_ABC
  A11  = M_C_MA<11>
  A7  = M_C_MA<7>
  VDD(9)  = PVDDQ_ABC
  A5  = M_C_MA<5>
  A4  = M_C_MA<4>
  VDD(8)  = PVDDQ_ABC
  A2  = M_C_MA<2>
  VDD(7)  = PVDDQ_ABC
  CK1P  = M_C_CLK_DP<1>
  CK1N  = M_C_CLK_DN<1>
  VDD(6)  = PVDDQ_ABC
  VTT(0)  = PVTT_ABC
  PAR  = M_C_PAR
  VDD(5)  = PVDDQ_ABC
  BA(1)  = M_C_BA<1>
  A10  = M_C_MA<10>
  VDD(4)  = PVDDQ_ABC
  RFU(1)  = TP_CH_C_DIMM_C0_RFU_1
  A14_WE_N  = M_C_MA<14>
  VDD(3)  = PVDDQ_ABC
  SAVE_N_NC  = FM_ADR_COMPLETE_ABC_N
  VDD(2)  = PVDDQ_ABC
  A13  = M_C_MA<13>
  VDD(1)  = PVDDQ_ABC
  A17  = M_C_MA<17>
  C(2)  = M_C_C<2>
  VDD(0)  = PVDDQ_ABC
  S3_N_C(1)  = M_C_CS_N<3>
  SA(2)  = PVPP_ABC
  VSS(20)  = GND
  DQ(37)  = M_C_DQ<36>
  VSS(19)  = GND
  DQ(33)  = M_C_DQ<32>
  VSS(18)  = GND
  DQS4N  = M_C_DQS_DN<4>
  DQS4P  = M_C_DQS_DP<4>
  VSS(17)  = GND
  DQ(39)  = M_C_DQ<38>
  VSS(16)  = GND
  DQ(35)  = M_C_DQ<34>
  VSS(15)  = GND
  DQ(45)  = M_C_DQ<44>
  VSS(14)  = GND
  DQ(41)  = M_C_DQ<40>
  VSS(13)  = GND
  DQS5N  = M_C_DQS_DN<5>
  DQS5P  = M_C_DQS_DP<5>
  VSS(12)  = GND
  DQ(47)  = M_C_DQ<46>
  VSS(11)  = GND
  DQ(43)  = M_C_DQ<42>
  VSS(10)  = GND
  DQ(53)  = M_C_DQ<52>
  VSS(9)  = GND
  DQ(49)  = M_C_DQ<48>
  VSS(8)  = GND
  DQS6N  = M_C_DQS_DN<6>
  DQS6P  = M_C_DQS_DP<6>
  VSS(7)  = GND
  DQ(55)  = M_C_DQ<54>
  VSS(6)  = GND
  DQ(51)  = M_C_DQ<50>
  VSS(5)  = GND
  DQ(61)  = M_C_DQ<60>
  VSS(4)  = GND
  DQ(57)  = M_C_DQ<56>
  VSS(3)  = GND
  DQS7N  = M_C_DQS_DN<7>
  DQS7P  = M_C_DQS_DP<7>
  VSS(2)  = GND
  DQ(63)  = M_C_DQ<62>
  VSS(1)  = GND
  DQ(59)  = M_C_DQ<58>
  VSS(0)  = GND
  VDDSPD  = PVPP_ABC
  SDA  = SMB_DDR_ABC_VPP_SDA
  VPP(1)  = PVPP_ABC
  VPP(0)  = PVPP_ABC
  VPP(2)  = PVPP_ABC

(kicad_pcb
	(version 20260206)
	(generator "pcbnew")
	(generator_version "10.0")
	(general
		(thickness 1.6)
		(legacy_teardrops no)
	)
	(paper "A4")
	(title_block
		(title "Wiwynn_Tioga_Pass_MB.brd")
		(comment 1 "Tioga Pass / footprint 1441 of 4770 (J4G3), pads 102-152 of 291")
	)
	(layers
		(0 "F.Cu" signal "TOP")
		(4 "In1.Cu" signal "L2GND")
		(6 "In2.Cu" signal "L3")
		(8 "In3.Cu" signal "L4GND")
		(10 "In4.Cu" signal "L5")
		(12 "In5.Cu" signal "L6GND")
		(14 "In6.Cu" signal "L7VCC")
		(16 "In7.Cu" signal "L8VCC")
		(18 "In8.Cu" signal "L9GND")
		(20 "In9.Cu" signal "L10")
		(22 "In10.Cu" signal "L11GND")
		(24 "In11.Cu" signal "L12")
		(26 "In12.Cu" signal "L13GND")
		(2 "B.Cu" signal "BOTTOM")
		(9 "F.Adhes" user "F.Adhesive")
		(11 "B.Adhes" user "B.Adhesive")
		(13 "F.Paste" user "Package Geometry/Pastemask Top")
		(15 "B.Paste" user "Package Geometry/Pastemask Bottom")
		(5 "F.SilkS" user "Ref Des/Silkscreen Top")
		(7 "B.SilkS" user "Ref Des/Silkscreen Bottom")
		(1 "F.Mask" user "Board Geometry/Soldermask Top")
		(3 "B.Mask" user "Board Geometry/Soldermask Bottom")
		(17 "Dwgs.User" user "User.Drawings")
		(19 "Cmts.User" user "User.Comments")
		(21 "Eco1.User" user "User.Eco1")
		(23 "Eco2.User" user "User.Eco2")
		(25 "Edge.Cuts" user "Board Geometry/Outline")
		(27 "Margin" user)
		(31 "F.CrtYd" user "Package Geometry/Place Bound Top")
		(29 "B.CrtYd" user "Package Geometry/Place Bound Bottom")
		(35 "F.Fab" user "Ref Des/Assembly Top")
		(33 "B.Fab" user "Ref Des/Assembly Bottom")
	)
	(footprint ""
		(layer "F.Cu")
		(at 194.700398 3.778758 90)
		(property "Reference" "J4G3"
			(at 6.800088 37.20211 0)
			(unlocked yes)
			(layer "F.SilkS")
			(effects
				(font
					(size 0.7874 0.5842)
					(thickness 0.1524)
				)
				(justify left)
			)
		)
		(property "Value" ""
			(at 0 0 90)
			(layer "F.Fab")
			(effects
				(font
					(size 1.27 1.27)
				)
			)
		)
		(duplicate_pad_numbers_are_jumpers no)
		(pad "99" smd rect
			(at 0 88.399874 90)
			(size 1.8034 0.508)
			(layers "F.Cu" "F.Mask" "F.Paste")
			(net "M_C_DQS_DP<13>")
		)
		(pad "100" smd rect
			(at 0 89.250012 90)
			(size 1.8034 0.508)
			(layers "F.Cu" "F.Mask" "F.Paste")
			(net "M_C_DQS_DN<13>")
		)
		(pad "101" smd rect
			(at 0 90.099896 90)
			(size 1.8034 0.508)
			(layers "F.Cu" "F.Mask" "F.Paste")
			(net "GND")
		)
		(pad "102" smd rect
			(at 0 90.950034 90)
			(size 1.8034 0.508)
			(layers "F.Cu" "F.Mask" "F.Paste")
			(net "M_C_DQ<39>")
		)
		(pad "103" smd rect
			(at 0 91.799918 90)
			(size 1.8034 0.508)
			(layers "F.Cu" "F.Mask" "F.Paste")
			(net "GND")
		)
		(pad "104" smd rect
			(at 0 92.650056 90)
			(size 1.8034 0.508)
			(layers "F.Cu" "F.Mask" "F.Paste")
			(net "M_C_DQ<35>")
		)
		(pad "105" smd rect
			(at 0 93.49994 90)
			(size 1.8034 0.508)
			(layers "F.Cu" "F.Mask" "F.Paste")
			(net "GND")
		)
		(pad "106" smd rect
			(at 0 94.350078 90)
			(size 1.8034 0.508)
			(layers "F.Cu" "F.Mask" "F.Paste")
			(net "M_C_DQ<45>")
		)
		(pad "107" smd rect
			(at 0 95.199962 90)
			(size 1.8034 0.508)
			(layers "F.Cu" "F.Mask" "F.Paste")
			(net "GND")
		)
		(pad "108" smd rect
			(at 0 96.0501 90)
			(size 1.8034 0.508)
			(layers "F.Cu" "F.Mask" "F.Paste")
			(net "M_C_DQ<41>")
		)
		(pad "109" smd rect
			(at 0 96.899984 90)
			(size 1.8034 0.508)
			(layers "F.Cu" "F.Mask" "F.Paste")
			(net "GND")
		)
		(pad "110" smd rect
			(at 0 97.750122 90)
			(size 1.8034 0.508)
			(layers "F.Cu" "F.Mask" "F.Paste")
			(net "M_C_DQS_DP<14>")
		)
		(pad "111" smd rect
			(at 0 98.600006 90)
			(size 1.8034 0.508)
			(layers "F.Cu" "F.Mask" "F.Paste")
			(net "M_C_DQS_DN<14>")
		)
		(pad "112" smd rect
			(at 0 99.44989 90)
			(size 1.8034 0.508)
			(layers "F.Cu" "F.Mask" "F.Paste")
			(net "GND")
		)
		(pad "113" smd rect
			(at 0 100.300028 90)
			(size 1.8034 0.508)
			(layers "F.Cu" "F.Mask" "F.Paste")
			(net "M_C_DQ<47>")
		)
		(pad "114" smd rect
			(at 0 101.149912 90)
			(size 1.8034 0.508)
			(layers "F.Cu" "F.Mask" "F.Paste")
			(net "GND")
		)
		(pad "115" smd rect
			(at 0 102.00005 90)
			(size 1.8034 0.508)
			(layers "F.Cu" "F.Mask" "F.Paste")
			(net "M_C_DQ<43>")
		)
		(pad "116" smd rect
			(at 0 102.849934 90)
			(size 1.8034 0.508)
			(layers "F.Cu" "F.Mask" "F.Paste")
			(net "GND")
		)
		(pad "117" smd rect
			(at 0 103.700072 90)
			(size 1.8034 0.508)
			(layers "F.Cu" "F.Mask" "F.Paste")
			(net "M_C_DQ<53>")
		)
		(pad "118" smd rect
			(at 0 104.549956 90)
			(size 1.8034 0.508)
			(layers "F.Cu" "F.Mask" "F.Paste")
			(net "GND")
		)
		(pad "119" smd rect
			(at 0 105.400094 90)
			(size 1.8034 0.508)
			(layers "F.Cu" "F.Mask" "F.Paste")
			(net "M_C_DQ<49>")
		)
		(pad "120" smd rect
			(at 0 106.249978 90)
			(size 1.8034 0.508)
			(layers "F.Cu" "F.Mask" "F.Paste")
			(net "GND")
		)
		(pad "121" smd rect
			(at 0 107.100116 90)
			(size 1.8034 0.508)
			(layers "F.Cu" "F.Mask" "F.Paste")
			(net "M_C_DQS_DP<15>")
		)
		(pad "122" smd rect
			(at 0 107.95 90)
			(size 1.8034 0.508)
			(layers "F.Cu" "F.Mask" "F.Paste")
			(net "M_C_DQS_DN<15>")
		)
		(pad "123" smd rect
			(at 0 108.799884 90)
			(size 1.8034 0.508)
			(layers "F.Cu" "F.Mask" "F.Paste")
			(net "GND")
		)
		(pad "124" smd rect
			(at 0 109.650022 90)
			(size 1.8034 0.508)
			(layers "F.Cu" "F.Mask" "F.Paste")
			(net "M_C_DQ<55>")
		)
		(pad "125" smd rect
			(at 0 110.499906 90)
			(size 1.8034 0.508)
			(layers "F.Cu" "F.Mask" "F.Paste")
			(net "GND")
		)
		(pad "126" smd rect
			(at 0 111.350044 90)
			(size 1.8034 0.508)
			(layers "F.Cu" "F.Mask" "F.Paste")
			(net "M_C_DQ<51>")
		)
		(pad "127" smd rect
			(at 0 112.199928 90)
			(size 1.8034 0.508)
			(layers "F.Cu" "F.Mask" "F.Paste")
			(net "GND")
		)
		(pad "128" smd rect
			(at 0 113.050066 90)
			(size 1.8034 0.508)
			(layers "F.Cu" "F.Mask" "F.Paste")
			(net "M_C_DQ<61>")
		)
		(pad "129" smd rect
			(at 0 113.89995 90)
			(size 1.8034 0.508)
			(layers "F.Cu" "F.Mask" "F.Paste")
			(net "GND")
		)
		(pad "130" smd rect
			(at 0 114.750088 90)
			(size 1.8034 0.508)
			(layers "F.Cu" "F.Mask" "F.Paste")
			(net "M_C_DQ<57>")
		)
		(pad "131" smd rect
			(at 0 115.599972 90)
			(size 1.8034 0.508)
			(layers "F.Cu" "F.Mask" "F.Paste")
			(net "GND")
		)
		(pad "132" smd rect
			(at 0 116.45011 90)
			(size 1.8034 0.508)
			(layers "F.Cu" "F.Mask" "F.Paste")
			(net "M_C_DQS_DP<16>")
		)
		(pad "133" smd rect
			(at 0 117.299994 90)
			(size 1.8034 0.508)
			(layers "F.Cu" "F.Mask" "F.Paste")
			(net "M_C_DQS_DN<16>")
		)
		(pad "134" smd rect
			(at 0 118.149878 90)
			(size 1.8034 0.508)
			(layers "F.Cu" "F.Mask" "F.Paste")
			(net "GND")
		)
		(pad "135" smd rect
			(at 0 119.000016 90)
			(size 1.8034 0.508)
			(layers "F.Cu" "F.Mask" "F.Paste")
			(net "M_C_DQ<63>")
		)
		(pad "136" smd rect
			(at 0 119.8499 90)
			(size 1.8034 0.508)
			(layers "F.Cu" "F.Mask" "F.Paste")
			(net "GND")
		)
		(pad "137" smd rect
			(at 0 120.700038 90)
			(size 1.8034 0.508)
			(layers "F.Cu" "F.Mask" "F.Paste")
			(net "M_C_DQ<59>")
		)
		(pad "138" smd rect
			(at 0 121.549922 90)
			(size 1.8034 0.508)
			(layers "F.Cu" "F.Mask" "F.Paste")
			(net "GND")
		)
		(pad "139" smd rect
			(at 0 122.40006 90)
			(size 1.8034 0.508)
			(layers "F.Cu" "F.Mask" "F.Paste")
			(net "GND")
		)
		(pad "140" smd rect
			(at 0 123.249944 90)
			(size 1.8034 0.508)
			(layers "F.Cu" "F.Mask" "F.Paste")
			(net "GND")
		)
		(pad "141" smd rect
			(at 0 124.100082 90)
			(size 1.8034 0.508)
			(layers "F.Cu" "F.Mask" "F.Paste")
			(net "SMB_DDR_ABC_VPP_SCL")
		)
		(pad "142" smd rect
			(at 0 124.949966 90)
			(size 1.8034 0.508)
			(layers "F.Cu" "F.Mask" "F.Paste")
			(net "PVPP_ABC")
		)
		(pad "143" smd rect
			(at 0 125.800104 90)
			(size 1.8034 0.508)
			(layers "F.Cu" "F.Mask" "F.Paste")
			(net "PVPP_ABC")
		)
		(pad "144" smd rect
			(at 0 126.649988 90)
			(size 1.8034 0.508)
			(layers "F.Cu" "F.Mask" "F.Paste")
			(net "TP_CH_C_DIMM_C0_RFU_2")
		)
		(pad "145" smd rect
			(at 4.59994 0 90)
			(size 1.8034 0.508)
			(layers "F.Cu" "F.Mask" "F.Paste")
			(net "P12V_NVDIMM_ABC")
		)
		(pad "146" smd rect
			(at 4.59994 0.849884 90)
			(size 1.8034 0.508)
			(layers "F.Cu" "F.Mask" "F.Paste")
			(net "M_C_VREF")
		)
		(pad "147" smd rect
			(at 4.59994 1.700022 90)
			(size 1.8034 0.508)
			(layers "F.Cu" "F.Mask" "F.Paste")
			(net "GND")
		)
		(pad "148" smd rect
			(at 4.59994 2.549906 90)
			(size 1.8034 0.508)
			(layers "F.Cu" "F.Mask" "F.Paste")
			(net "M_C_DQ<4>")
		)
		(pad "149" smd rect
			(at 4.59994 3.400044 90)
			(size 1.8034 0.508)
			(layers "F.Cu" "F.Mask" "F.Paste")
			(net "GND")
		)
	)
)
